(kicad_pcb
	(version 20240108)
	(generator "pcbnew")
	(generator_version "8.0")
	(general
		(thickness 1.586)
		(legacy_teardrops no)
	)
	(paper "A4")
	(title_block
		(title "GMSL Serializer")
		(date "2024-11-27")
		(rev "1.1.1")
		(company "Antmicro Ltd")
		(comment 1 "www.antmicro.com")
		(comment 9 "footprints 20-24 of 117")
	)
	(layers
		(0 "F.Cu" signal)
		(1 "In1.Cu" power)
		(2 "In2.Cu" power)
		(31 "B.Cu" signal)
		(32 "B.Adhes" user "B.Adhesive")
		(33 "F.Adhes" user "F.Adhesive")
		(34 "B.Paste" user)
		(35 "F.Paste" user)
		(36 "B.SilkS" user "B.Silkscreen")
		(37 "F.SilkS" user "F.Silkscreen")
		(38 "B.Mask" user)
		(39 "F.Mask" user)
		(40 "Dwgs.User" user "User.Drawings")
		(41 "Cmts.User" user "User.Comments")
		(42 "Eco1.User" user "User.Eco1")
		(43 "Eco2.User" user "User.Eco2")
		(44 "Edge.Cuts" user)
		(45 "Margin" user)
		(46 "B.CrtYd" user "B.Courtyard")
		(47 "F.CrtYd" user "F.Courtyard")
		(48 "B.Fab" user)
		(49 "F.Fab" user)
	)
	(footprint "antmicro-footprints:TP_SMD_1.5mm"
		(layer "F.Cu")
		(at 150.5 118)
		(property "Reference" "TP5"
			(at -0.4 -1 0)
			(layer "F.SilkS")
			(hide yes)
			(effects
				(font
					(size 0.7 0.7)
					(thickness 0.15)
				)
				(justify left bottom)
			)
		)
		(property "Value" "TP_1.5mm_SMD"
			(at 0 1.7 0)
			(layer "F.Fab")
			(effects
				(font
					(size 0.7 0.7)
					(thickness 0.15)
				)
				(justify left bottom)
			)
		)
		(property "Footprint" "antmicro-footprints:TP_SMD_1.5mm"
			(at 0 0 0)
			(layer "F.Fab")
			(hide yes)
			(effects
				(font
					(size 1.27 1.27)
					(thickness 0.15)
				)
			)
		)
		(property "Author" "Antmicro"
			(at 0 0 0)
			(layer "F.Fab")
			(hide yes)
			(effects
				(font
					(size 1 1)
					(thickness 0.15)
				)
			)
		)
		(property "License" "Apache-2.0"
			(at 0 0 0)
			(layer "F.Fab")
			(hide yes)
			(effects
				(font
					(size 1 1)
					(thickness 0.15)
				)
			)
		)
		(property "MPN" ""
			(at 0 0 0)
			(layer "F.Fab")
			(hide yes)
			(effects
				(font
					(size 1 1)
					(thickness 0.15)
				)
			)
		)
		(property "Manufacturer" ""
			(at 0 0 0)
			(layer "F.Fab")
			(hide yes)
			(effects
				(font
					(size 1 1)
					(thickness 0.15)
				)
			)
		)
		(sheetname "Supply")
		(sheetfile "supply.kicad_sch")
		(attr exclude_from_pos_files exclude_from_bom)
		(fp_circle
			(center 0 0)
			(end 0.85 0)
			(stroke
				(width 0.05)
				(type default)
			)
			(fill none)
			(layer "F.CrtYd")
		)
		(fp_text user "License: Apache-2.0"
			(at -0.7 5.301 0)
			(layer "F.Fab")
			(hide yes)
			(effects
				(font
					(size 0.7 0.7)
					(thickness 0.15)
				)
				(justify left bottom)
			)
		)
		(fp_text user "${REFERENCE}"
			(at -0.7 2.9 0)
			(layer "F.Fab")
			(hide yes)
			(effects
				(font
					(size 0.7 0.7)
					(thickness 0.15)
				)
				(justify left bottom)
			)
		)
		(fp_text user "Author: Antmicro"
			(at -0.7 4.101 0)
			(layer "F.Fab")
			(hide yes)
			(effects
				(font
					(size 0.7 0.7)
					(thickness 0.15)
				)
				(justify left bottom)
			)
		)
		(pad "1" smd circle
			(at 0 0 270)
			(size 1.5 1.5)
			(layers "F.Cu" "F.Mask")
			(net 12 "+1V2")
			(pinfunction "1")
			(pintype "passive")
		)
	)
	(footprint "antmicro-footprints:R_0402_1005Metric"
		(layer "F.Cu")
		(at 135.4 111.98)
		(descr "Resistor SMD 0402")
		(tags "resistor SMD 0402")
		(property "Reference" "R6"
			(at 0.9 0.37 0)
			(layer "F.SilkS")
			(effects
				(font
					(size 0.7 0.7)
					(thickness 0.15)
				)
				(justify left bottom)
			)
		)
		(property "Value" "R_4k7_0402"
			(at -1.011843 1.772047 0)
			(layer "F.Fab")
			(effects
				(font
					(size 0.7 0.7)
					(thickness 0.15)
				)
				(justify left bottom)
			)
		)
		(property "Footprint" "antmicro-footprints:R_0402_1005Metric"
			(at 0 0 0)
			(layer "F.Fab")
			(hide yes)
			(effects
				(font
					(size 1.27 1.27)
					(thickness 0.15)
				)
			)
		)
		(property "Datasheet" "https://www.bourns.com/docs/product-datasheets/cr.pdf"
			(at 0 0 0)
			(layer "F.Fab")
			(hide yes)
			(effects
				(font
					(size 1.27 1.27)
					(thickness 0.15)
				)
			)
		)
		(property "Author" "Antmicro"
			(at 0 0 0)
			(layer "F.Fab")
			(hide yes)
			(effects
				(font
					(size 1 1)
					(thickness 0.15)
				)
			)
		)
		(property "License" "Apache-2.0"
			(at 0 0 0)
			(layer "F.Fab")
			(hide yes)
			(effects
				(font
					(size 1 1)
					(thickness 0.15)
				)
			)
		)
		(property "MPN" "CR0402-FX-4701GLF"
			(at 0 0 0)
			(layer "F.Fab")
			(hide yes)
			(effects
				(font
					(size 1 1)
					(thickness 0.15)
				)
			)
		)
		(property "Manufacturer" "Bourns"
			(at 0 0 0)
			(layer "F.Fab")
			(hide yes)
			(effects
				(font
					(size 1 1)
					(thickness 0.15)
				)
			)
		)
		(property "Tolerance" "1%"
			(at 0 0 0)
			(layer "F.Fab")
			(hide yes)
			(effects
				(font
					(size 1 1)
					(thickness 0.15)
				)
			)
		)
		(property "Val" "4k7"
			(at 0 0 0)
			(layer "F.Fab")
			(hide yes)
			(effects
				(font
					(size 1 1)
					(thickness 0.15)
				)
			)
		)
		(sheetname "CSI Connector")
		(sheetfile "CSI.kicad_sch")
		(attr smd)
		(fp_rect
			(start -0.925 -0.47)
			(end 0.925 0.47)
			(stroke
				(width 0.05)
				(type default)
			)
			(fill none)
			(layer "F.CrtYd")
		)
		(fp_rect
			(start -0.5 -0.25)
			(end 0.5 0.25)
			(stroke
				(width 0.15)
				(type solid)
			)
			(fill none)
			(layer "F.Fab")
		)
		(fp_text user "Author: Antmicro"
			(at -0.95 4.169 0)
			(layer "F.Fab")
			(hide yes)
			(effects
				(font
					(size 0.7 0.7)
					(thickness 0.15)
				)
				(justify left bottom)
			)
		)
		(fp_text user "License: Apache-2.0"
			(at -0.95 5.169 0)
			(layer "F.Fab")
			(hide yes)
			(effects
				(font
					(size 0.7 0.7)
					(thickness 0.15)
				)
				(justify left bottom)
			)
		)
		(fp_text user "${REFERENCE}"
			(at -0.95 3.168 0)
			(layer "F.Fab")
			(hide yes)
			(effects
				(font
					(size 0.7 0.7)
					(thickness 0.15)
				)
				(justify left bottom)
			)
		)
		(pad "1" smd roundrect
			(at -0.48 0)
			(size 0.59 0.64)
			(layers "F.Cu" "F.Paste" "F.Mask")
			(roundrect_rratio 0.25)
			(net 89 "/CSI Connector/I2C.SCL")
			(pintype "passive")
		)
		(pad "2" smd roundrect
			(at 0.48 0)
			(size 0.59 0.64)
			(layers "F.Cu" "F.Paste" "F.Mask")
			(roundrect_rratio 0.25)
			(net 10 "+3V3")
			(pintype "passive")
		)
	)
	(footprint "antmicro-footprints:C_0402_1005Metric"
		(layer "F.Cu")
		(at 152.53 109.34)
		(descr "Capacitor SMD 0402")
		(tags "capacitor SMD 0402")
		(property "Reference" "C12"
			(at 0.94 0.39 0)
			(layer "F.SilkS")
			(effects
				(font
					(size 0.7 0.7)
					(thickness 0.15)
				)
				(justify left bottom)
			)
		)
		(property "Value" "C_1u_16V_0402"
			(at -1.022927 2.155213 0)
			(layer "F.Fab")
			(effects
				(font
					(size 0.7 0.7)
					(thickness 0.15)
				)
				(justify left bottom)
			)
		)
		(property "Footprint" "antmicro-footprints:C_0402_1005Metric"
			(at 0 0 0)
			(layer "F.Fab")
			(hide yes)
			(effects
				(font
					(size 1.27 1.27)
					(thickness 0.15)
				)
			)
		)
		(property "Datasheet" "https://www.kemet.com/en/us/capacitors/product/C0402C105M4PACTU.html"
			(at 0 0 0)
			(layer "F.Fab")
			(hide yes)
			(effects
				(font
					(size 1.27 1.27)
					(thickness 0.15)
				)
			)
		)
		(property "Author" "Antmicro"
			(at 0 0 0)
			(layer "F.Fab")
			(hide yes)
			(effects
				(font
					(size 1 1)
					(thickness 0.15)
				)
			)
		)
		(property "Dielectric" ""
			(at 0 0 0)
			(layer "F.Fab")
			(hide yes)
			(effects
				(font
					(size 1 1)
					(thickness 0.15)
				)
			)
		)
		(property "License" "Apache-2.0"
			(at 0 0 0)
			(layer "F.Fab")
			(hide yes)
			(effects
				(font
					(size 1 1)
					(thickness 0.15)
				)
			)
		)
		(property "MPN" "C0402C105M4PACTU"
			(at 0 0 0)
			(layer "F.Fab")
			(hide yes)
			(effects
				(font
					(size 1 1)
					(thickness 0.15)
				)
			)
		)
		(property "Manufacturer" "KEMET"
			(at 0 0 0)
			(layer "F.Fab")
			(hide yes)
			(effects
				(font
					(size 1 1)
					(thickness 0.15)
				)
			)
		)
		(property "Val" "1u"
			(at 0 0 0)
			(layer "F.Fab")
			(hide yes)
			(effects
				(font
					(size 1 1)
					(thickness 0.15)
				)
			)
		)
		(property "Voltage" "16V"
			(at 0 0 0)
			(layer "F.Fab")
			(hide yes)
			(effects
				(font
					(size 1 1)
					(thickness 0.15)
				)
			)
		)
		(sheetname "Supply")
		(sheetfile "supply.kicad_sch")
		(attr smd dnp)
		(fp_rect
			(start -0.925 -0.47)
			(end 0.925 0.47)
			(stroke
				(width 0.05)
				(type default)
			)
			(fill none)
			(layer "F.CrtYd")
		)
		(fp_line
			(start -0.494 -0.25)
			(end 0.504 -0.25)
			(stroke
				(width 0.15)
				(type solid)
			)
			(layer "F.Fab")
		)
		(fp_line
			(start -0.494 0.248)
			(end -0.494 -0.25)
			(stroke
				(width 0.15)
				(type solid)
			)
			(layer "F.Fab")
		)
		(fp_line
			(start 0.504 -0.25)
			(end 0.504 0.248)
			(stroke
				(width 0.15)
				(type solid)
			)
			(layer "F.Fab")
		)
		(fp_line
			(start 0.504 0.248)
			(end -0.494 0.248)
			(stroke
				(width 0.15)
				(type solid)
			)
			(layer "F.Fab")
		)
		(fp_text user "${REFERENCE}"
			(at -0.939 4.599 0)
			(layer "F.Fab")
			(hide yes)
			(effects
				(font
					(size 0.7 0.7)
					(thickness 0.15)
				)
				(justify left bottom)
			)
		)
		(fp_text user "License: Apache-2.0"
			(at -0.939 5.799 0)
			(layer "F.Fab")
			(hide yes)
			(effects
				(font
					(size 0.7 0.7)
					(thickness 0.15)
				)
				(justify left bottom)
			)
		)
		(fp_text user "Author: Antmicro"
			(at -0.939 3.399 0)
			(layer "F.Fab")
			(hide yes)
			(effects
				(font
					(size 0.7 0.7)
					(thickness 0.15)
				)
				(justify left bottom)
			)
		)
		(pad "1" smd roundrect
			(at -0.48 0)
			(size 0.59 0.64)
			(layers "F.Cu" "F.Paste" "F.Mask")
			(roundrect_rratio 0.25)
			(net 1 "GND")
			(pintype "passive")
		)
		(pad "2" smd roundrect
			(at 0.48 0)
			(size 0.59 0.64)
			(layers "F.Cu" "F.Paste" "F.Mask")
			(roundrect_rratio 0.25)
			(net 9 "+5V")
			(pintype "passive")
		)
	)
	(footprint "antmicro-footprints:R_0402_1005Metric"
		(layer "F.Cu")
		(at 149.345 115.95 90)
		(descr "Resistor SMD 0402")
		(tags "resistor SMD 0402")
		(property "Reference" "R35"
			(at -2.875 0.325 90)
			(layer "F.SilkS")
			(effects
				(font
					(size 0.7 0.7)
					(thickness 0.15)
				)
				(justify left bottom)
			)
		)
		(property "Value" "R_470R_0402"
			(at -1.011843 1.772047 90)
			(layer "F.Fab")
			(effects
				(font
					(size 0.7 0.7)
					(thickness 0.15)
				)
				(justify left bottom)
			)
		)
		(property "Footprint" "antmicro-footprints:R_0402_1005Metric"
			(at 0 0 90)
			(layer "F.Fab")
			(hide yes)
			(effects
				(font
					(size 1.27 1.27)
					(thickness 0.15)
				)
			)
		)
		(property "Datasheet" "https://www.bourns.com/docs/product-datasheets/cr.pdf"
			(at 0 0 90)
			(layer "F.Fab")
			(hide yes)
			(effects
				(font
					(size 1.27 1.27)
					(thickness 0.15)
				)
			)
		)
		(property "Author" "Antmicro"
			(at 265.295 -33.395 0)
			(layer "F.Fab")
			(hide yes)
			(effects
				(font
					(size 1 1)
					(thickness 0.15)
				)
			)
		)
		(property "License" "Apache-2.0"
			(at 265.295 -33.395 0)
			(layer "F.Fab")
			(hide yes)
			(effects
				(font
					(size 1 1)
					(thickness 0.15)
				)
			)
		)
		(property "MPN" "CR0402-FX-4700GLF"
			(at 265.295 -33.395 0)
			(layer "F.Fab")
			(hide yes)
			(effects
				(font
					(size 1 1)
					(thickness 0.15)
				)
			)
		)
		(property "Manufacturer" "Bourns"
			(at 265.295 -33.395 0)
			(layer "F.Fab")
			(hide yes)
			(effects
				(font
					(size 1 1)
					(thickness 0.15)
				)
			)
		)
		(property "Tolerance" "1%"
			(at 265.295 -33.395 0)
			(layer "F.Fab")
			(hide yes)
			(effects
				(font
					(size 1 1)
					(thickness 0.15)
				)
			)
		)
		(property "Val" "470R"
			(at 265.295 -33.395 0)
			(layer "F.Fab")
			(hide yes)
			(effects
				(font
					(size 1 1)
					(thickness 0.15)
				)
			)
		)
		(sheetname "Supply")
		(sheetfile "supply.kicad_sch")
		(attr smd)
		(fp_rect
			(start -0.925 -0.47)
			(end 0.925 0.47)
			(stroke
				(width 0.05)
				(type default)
			)
			(fill none)
			(layer "F.CrtYd")
		)
		(fp_rect
			(start -0.5 -0.25)
			(end 0.5 0.25)
			(stroke
				(width 0.15)
				(type solid)
			)
			(fill none)
			(layer "F.Fab")
		)
		(fp_text user "License: Apache-2.0"
			(at -0.95 5.169 90)
			(layer "F.Fab")
			(hide yes)
			(effects
				(font
					(size 0.7 0.7)
					(thickness 0.15)
				)
				(justify left bottom)
			)
		)
		(fp_text user "${REFERENCE}"
			(at -0.95 3.168 90)
			(layer "F.Fab")
			(hide yes)
			(effects
				(font
					(size 0.7 0.7)
					(thickness 0.15)
				)
				(justify left bottom)
			)
		)
		(fp_text user "Author: Antmicro"
			(at -0.95 4.169 90)
			(layer "F.Fab")
			(hide yes)
			(effects
				(font
					(size 0.7 0.7)
					(thickness 0.15)
				)
				(justify left bottom)
			)
		)
		(pad "1" smd roundrect
			(at -0.48 0 90)
			(size 0.59 0.64)
			(layers "F.Cu" "F.Paste" "F.Mask")
			(roundrect_rratio 0.25)
			(net 71 "Net-(D6-A)")
			(pintype "passive")
		)
		(pad "2" smd roundrect
			(at 0.48 0 90)
			(size 0.59 0.64)
			(layers "F.Cu" "F.Paste" "F.Mask")
			(roundrect_rratio 0.25)
			(net 9 "+5V")
			(pintype "passive")
		)
	)
	(footprint "antmicro-footprints:Resonator_SMD_Abracon_ABM8G_3.2x2.5mm"
		(layer "F.Cu")
		(at 154.686 101.854 45)
		(property "Reference" "Y1"
			(at 2.063338 1.562706 -135)
			(layer "F.SilkS")
			(effects
				(font
					(size 0.7 0.7)
					(thickness 0.15)
				)
				(justify left bottom)
			)
		)
		(property "Value" "Resonator_25MHz_ABM8G"
			(at -1.75 2.548 45)
			(layer "F.Fab")
			(effects
				(font
					(size 0.7 0.7)
					(thickness 0.15)
				)
				(justify left bottom)
			)
		)
		(property "Footprint" "antmicro-footprints:Resonator_SMD_Abracon_ABM8G_3.2x2.5mm"
			(at 0 0 45)
			(layer "F.Fab")
			(hide yes)
			(effects
				(font
					(size 1.27 1.27)
					(thickness 0.15)
				)
			)
		)
		(property "Datasheet" "https://abracon.com/Resonators/ABM8G.pdf"
			(at 0 0 45)
			(layer "F.Fab")
			(hide yes)
			(effects
				(font
					(size 1.27 1.27)
					(thickness 0.15)
				)
			)
		)
		(property "Author" "Antmicro"
			(at 117.328134 -79.547173 0)
			(layer "F.Fab")
			(hide yes)
			(effects
				(font
					(size 1 1)
					(thickness 0.15)
				)
			)
		)
		(property "License" "Apache-2.0"
			(at 117.328134 -79.547173 0)
			(layer "F.Fab")
			(hide yes)
			(effects
				(font
					(size 1 1)
					(thickness 0.15)
				)
			)
		)
		(property "MPN" "ABM8G-25.000MHZ-18-D2Y-T3"
			(at 117.328134 -79.547173 0)
			(layer "F.Fab")
			(hide yes)
			(effects
				(font
					(size 1 1)
					(thickness 0.15)
				)
			)
		)
		(property "Manufacturer" "Abracon"
			(at 117.328134 -79.547173 0)
			(layer "F.Fab")
			(hide yes)
			(effects
				(font
					(size 1 1)
					(thickness 0.15)
				)
			)
		)
		(property "Val" "25 MHz"
			(at 117.328134 -79.547173 0)
			(layer "F.Fab")
			(hide yes)
			(effects
				(font
					(size 1 1)
					(thickness 0.15)
				)
			)
		)
		(sheetname "Serializer")
		(sheetfile "serializer.kicad_sch")
		(attr smd)
		(fp_line
			(start -0.35 -1.25)
			(end 0.450001 -1.25)
			(stroke
				(width 0.15)
				(type solid)
			)
			(layer "F.SilkS")
		)
		(fp_line
			(start -1.6 0.3)
			(end -1.6 -0.2)
			(stroke
				(width 0.15)
				(type solid)
			)
			(layer "F.SilkS")
		)
		(fp_line
			(start -0.35 1.25)
			(end 0.450001 1.25)
			(stroke
				(width 0.15)
				(type solid)
			)
			(layer "F.SilkS")
		)
		(fp_line
			(start 1.6 0.3)
			(end 1.6 -0.2)
			(stroke
				(width 0.15)
				(type solid)
			)
			(layer "F.SilkS")
		)
		(fp_circle
			(center -1.75 1.5)
			(end -1.7 1.5)
			(stroke
				(width 0.15)
				(type solid)
			)
			(fill none)
			(layer "F.SilkS")
		)
		(fp_poly
			(pts
				(xy -1.907 -1.55) (xy 2.006 -1.55) (xy 2.006 1.649) (xy -1.907001 1.649)
			)
			(stroke
				(width 0.05)
				(type solid)
			)
			(fill none)
			(layer "F.CrtYd")
		)
		(fp_text user "Author: Antmicro"
			(at -1.75 5 45)
			(layer "F.Fab")
			(hide yes)
			(effects
				(font
					(size 0.7 0.7)
					(thickness 0.15)
				)
				(justify left bottom)
			)
		)
		(fp_text user "${REFERENCE}"
			(at -1.749999 3.75 45)
			(layer "F.Fab")
			(hide yes)
			(effects
				(font
					(size 0.7 0.7)
					(thickness 0.15)
				)
				(justify left bottom)
			)
		)
		(fp_text user "License: Apache-2.0"
			(at -1.75 6.5 45)
			(layer "F.Fab")
			(hide yes)
			(effects
				(font
					(size 0.7 0.7)
					(thickness 0.15)
				)
				(justify left bottom)
			)
		)
		(pad "1" smd roundrect
			(at -1.101 0.949 45)
			(size 1.3 1.1)
			(layers "F.Cu" "F.Paste" "F.Mask")
			(roundrect_rratio 0)
			(chamfer_ratio 0.2)
			(chamfer bottom_left)
			(net 13 "/Serializer/X1")
			(pintype "passive")
		)
		(pad "2" smd rect
			(at 1.199 0.949 45)
			(size 1.3 1.1)
			(layers "F.Cu" "F.Paste" "F.Mask")
			(net 1 "GND")
			(pinfunction "SH")
			(pintype "passive")
		)
		(pad "3" smd rect
			(at 1.199 -0.85 45)
			(size 1.3 1.1)
			(layers "F.Cu" "F.Paste" "F.Mask")
			(net 14 "/Serializer/X2_R")
			(pintype "passive")
		)
		(pad "4" smd rect
			(at -1.101 -0.85 45)
			(size 1.3 1.1)
			(layers "F.Cu" "F.Paste" "F.Mask")
			(net 1 "GND")
			(pinfunction "SH")
			(pintype "passive")
		)
	)
)
